# T6G (Grand Teton) — schematic netlist excerpt (pin names and nets, part order shuffled) for the footprints in the layout excerpt that follows; sources: Cadence DE-HDL packaged netlist, KiCad conversion of 04192023_DAF0TMB3IC0_F0TG_MB_C_brd_V02_OCP.brd

H97  HOLE  EMPTY  pkg TH  page 230 : \1\ = GND
R725  Q_RES  4.7K 5% CHIP  pkg 0201LF  page 320 : A = TEST2_RT_CPU1_P0 ; B = GND

U35  74LVC1G08W57  74LVC1G08W5-7 IC  pkg SOT25-5_0-95_3X1-6  page 142
  A  = RST_PERST_OCP_V3_2_R_N
  B  = HP_LVC3_OCP_V3_2_PWRGD
  GND  = GND
  Y  = RST_PERST_OCP_V3_2_BUF_R_N
  VCC  = P3V3_AUX

R1096  Q_RES  0 5% CHIP  pkg 0201LF  page 309 : A = RST_RT_CPU0_P3_RESET_N ; B = RST_RT_CPU0_P3_RESET_R_N
H103  HOLE  EMPTY  pkg TH  page 230 : \1\ = GND

(kicad_pcb
	(version 20260206)
	(generator "pcbnew")
	(generator_version "10.0")
	(general
		(thickness 1.6)
		(legacy_teardrops no)
	)
	(paper "A4")
	(title_block
		(title "04192023_DAF0TMB3IC0_F0TG_MB_C_brd_V02_OCP.brd")
		(comment 1 "Grand Teton / footprints 3385-3389 of 8354")
	)
	(layers
		(0 "F.Cu" signal "TOP")
		(4 "In1.Cu" signal "GND")
		(6 "In2.Cu" signal "IN1")
		(8 "In3.Cu" signal "GND1")
		(10 "In4.Cu" signal "IN2")
		(12 "In5.Cu" signal "GND2")
		(14 "In6.Cu" signal "IN3")
		(16 "In7.Cu" signal "GND3")
		(18 "In8.Cu" signal "VCC")
		(20 "In9.Cu" signal "VCC1")
		(22 "In10.Cu" signal "GND4")
		(24 "In11.Cu" signal "IN4")
		(26 "In12.Cu" signal "GND5")
		(28 "In13.Cu" signal "IN5")
		(30 "In14.Cu" signal "GND6")
		(32 "In15.Cu" signal "IN6")
		(34 "In16.Cu" signal "GND7")
		(2 "B.Cu" signal "BOTTOM")
		(9 "F.Adhes" user "F.Adhesive")
		(11 "B.Adhes" user "B.Adhesive")
		(13 "F.Paste" user "Package Geometry/Pastemask Top")
		(15 "B.Paste" user "Package Geometry/Pastemask Bottom")
		(5 "F.SilkS" user "Ref Des/Silkscreen Top")
		(7 "B.SilkS" user "Ref Des/Silkscreen Bottom")
		(1 "F.Mask" user "Board Geometry/Soldermask Top")
		(3 "B.Mask" user "Board Geometry/Soldermask Bottom")
		(17 "Dwgs.User" user "User.Drawings")
		(19 "Cmts.User" user "User.Comments")
		(21 "Eco1.User" user "User.Eco1")
		(23 "Eco2.User" user "User.Eco2")
		(25 "Edge.Cuts" user "Board Geometry/Outline")
		(27 "Margin" user)
		(31 "F.CrtYd" user "Package Geometry/Place Bound Top")
		(29 "B.CrtYd" user "Package Geometry/Place Bound Bottom")
		(35 "F.Fab" user "Ref Des/Assembly Top")
		(33 "B.Fab" user "Ref Des/Assembly Bottom")
	)
	(footprint ""
		(layer "F.Cu")
		(at 366.822736 -403.285452 90)
		(property "Reference" "R1096"
			(at 0 0 90)
			(layer "F.SilkS")
			(hide yes)
			(effects
				(font
					(size 1.27 1.27)
				)
			)
		)
		(property "Value" ""
			(at 0 0 90)
			(layer "F.Fab")
			(effects
				(font
					(size 1.27 1.27)
				)
			)
		)
		(duplicate_pad_numbers_are_jumpers no)
		(fp_line
			(start 0.32512 -0.175006)
			(end 0.32512 0.175006)
			(stroke
				(width 0.1)
				(type default)
			)
			(layer "F.Fab")
		)
		(fp_line
			(start -0.32512 -0.175006)
			(end 0.32512 -0.175006)
			(stroke
				(width 0.1)
				(type default)
			)
			(layer "F.Fab")
		)
		(fp_line
			(start 0.32512 0.175006)
			(end -0.32512 0.175006)
			(stroke
				(width 0.1)
				(type default)
			)
			(layer "F.Fab")
		)
		(fp_line
			(start -0.32512 0.175006)
			(end -0.32512 -0.175006)
			(stroke
				(width 0.1)
				(type default)
			)
			(layer "F.Fab")
		)
		(pad "1" smd rect
			(at -0.2667 0 90)
			(size 0.3048 0.381)
			(layers "F.Cu" "F.Mask" "F.Paste")
			(net "RST_RT_CPU0_P3_RESET_N")
		)
		(pad "2" smd rect
			(at 0.2667 0 270)
			(size 0.3048 0.381)
			(layers "F.Cu" "F.Mask" "F.Paste")
			(net "RST_RT_CPU0_P3_RESET_R_N")
		)
	)
	(footprint ""
		(layer "F.Cu")
		(at 43.265852 -383.7432)
		(property "Reference" "R725"
			(at 0 0 0)
			(layer "F.SilkS")
			(hide yes)
			(effects
				(font
					(size 1.27 1.27)
				)
			)
		)
		(property "Value" ""
			(at 0 0 0)
			(layer "F.Fab")
			(effects
				(font
					(size 1.27 1.27)
				)
			)
		)
		(duplicate_pad_numbers_are_jumpers no)
		(fp_line
			(start -0.32512 -0.175006)
			(end 0.32512 -0.175006)
			(stroke
				(width 0.1)
				(type default)
			)
			(layer "F.Fab")
		)
		(fp_line
			(start -0.32512 0.175006)
			(end -0.32512 -0.175006)
			(stroke
				(width 0.1)
				(type default)
			)
			(layer "F.Fab")
		)
		(fp_line
			(start 0.32512 -0.175006)
			(end 0.32512 0.175006)
			(stroke
				(width 0.1)
				(type default)
			)
			(layer "F.Fab")
		)
		(fp_line
			(start 0.32512 0.175006)
			(end -0.32512 0.175006)
			(stroke
				(width 0.1)
				(type default)
			)
			(layer "F.Fab")
		)
		(pad "1" smd rect
			(at -0.2667 0)
			(size 0.3048 0.381)
			(layers "F.Cu" "F.Mask" "F.Paste")
			(net "TEST2_RT_CPU1_P0")
		)
		(pad "2" smd rect
			(at 0.2667 0 180)
			(size 0.3048 0.381)
			(layers "F.Cu" "F.Mask" "F.Paste")
			(net "GND")
		)
	)
	(footprint ""
		(layer "F.Cu")
		(at 12.99972 -435.600094)
		(property "Reference" "H97"
			(at 4.924044 -4.168394 0)
			(unlocked yes)
			(layer "F.SilkS")
			(effects
				(font
					(size 0.7874 0.5842)
					(thickness 0.1524)
				)
				(justify left)
			)
		)
		(property "Value" ""
			(at 0 0 0)
			(layer "F.Fab")
			(effects
				(font
					(size 1.27 1.27)
				)
			)
		)
		(duplicate_pad_numbers_are_jumpers no)
		(pad "1" thru_hole circle
			(at 0 0)
			(size 10.0076 10.0076)
			(drill 5.6134)
			(layers "*.Cu" "*.Mask")
			(remove_unused_layers no)
			(net "GND")
			(clearance -1.9431)
		)
	)
	(footprint ""
		(layer "F.Cu")
		(at 458.799692 -435.600094)
		(property "Reference" "H103"
			(at -6.63321 -4.534154 0)
			(unlocked yes)
			(layer "F.SilkS")
			(effects
				(font
					(size 0.7874 0.5842)
					(thickness 0.1524)
				)
				(justify left)
			)
		)
		(property "Value" ""
			(at 0 0 0)
			(layer "F.Fab")
			(effects
				(font
					(size 1.27 1.27)
				)
			)
		)
		(duplicate_pad_numbers_are_jumpers no)
		(pad "1" thru_hole circle
			(at 0 0)
			(size 10.0076 10.0076)
			(drill 5.6134)
			(layers "*.Cu" "*.Mask")
			(remove_unused_layers no)
			(net "GND")
			(clearance -1.9431)
		)
	)
	(footprint ""
		(layer "F.Cu")
		(at 73.406 -59.055 -90)
		(property "Reference" "U35"
			(at 0.943102 -2.804668 90)
			(unlocked yes)
			(layer "F.SilkS")
			(effects
				(font
					(size 0.7874 0.5842)
					(thickness 0.1524)
				)
				(justify left)
			)
		)
		(property "Value" ""
			(at 0 0 270)
			(layer "F.Fab")
			(effects
				(font
					(size 1.27 1.27)
				)
			)
		)
		(duplicate_pad_numbers_are_jumpers no)
		(fp_line
			(start -1.733296 1.549908)
			(end 1.733296 1.549908)
			(stroke
				(width 0.1524)
				(type default)
			)
			(layer "F.SilkS")
		)
		(fp_line
			(start 1.733296 1.549908)
			(end 1.733296 -1.549908)
			(stroke
				(width 0.1524)
				(type default)
			)
			(layer "F.SilkS")
		)
		(fp_line
			(start 0 -0.889)
			(end -0.660908 -1.549908)
			(stroke
				(width 0.1524)
				(type default)
			)
			(layer "F.SilkS")
		)
		(fp_line
			(start -1.733296 -1.549908)
			(end -1.733296 1.549908)
			(stroke
				(width 0.1524)
				(type default)
			)
			(layer "F.SilkS")
		)
		(fp_line
			(start -0.660908 -1.549908)
			(end -1.733296 -1.549908)
			(stroke
				(width 0.1524)
				(type default)
			)
			(layer "F.SilkS")
		)
		(fp_line
			(start 0.660908 -1.549908)
			(end 0 -0.889)
			(stroke
				(width 0.1524)
				(type default)
			)
			(layer "F.SilkS")
		)
		(fp_line
			(start 1.733296 -1.549908)
			(end 0.660908 -1.549908)
			(stroke
				(width 0.1524)
				(type default)
			)
			(layer "F.SilkS")
		)
		(fp_poly
			(pts
				(xy -1.80975 -2.293366) (xy -2.223262 -1.998218) (xy -1.721358 -1.73228)
			)
			(stroke
				(width 0)
				(type default)
			)
			(fill yes)
			(layer "F.SilkS")
		)
		(fp_line
			(start -0.849884 1.549908)
			(end 0.849884 1.549908)
			(stroke
				(width 0.1)
				(type default)
			)
			(layer "F.Fab")
		)
		(fp_line
			(start 0.849884 1.549908)
			(end 0.849884 -1.549908)
			(stroke
				(width 0.1)
				(type default)
			)
			(layer "F.Fab")
		)
		(fp_line
			(start -0.849884 -1.549908)
			(end -0.849884 1.549908)
			(stroke
				(width 0.1)
				(type default)
			)
			(layer "F.Fab")
		)
		(fp_line
			(start 0.849884 -1.549908)
			(end -0.849884 -1.549908)
			(stroke
				(width 0.1)
				(type default)
			)
			(layer "F.Fab")
		)
		(fp_poly
			(pts
				(xy -2.4384 -1.20396) (xy -2.4384 -0.69596) (xy -1.9304 -0.94996)
			)
			(stroke
				(width 0)
				(type default)
			)
			(fill yes)
			(layer "F.Fab")
		)
		(pad "1" smd rect
			(at -1.199896 -0.94996 180)
			(size 0.5588 0.8128)
			(layers "F.Cu" "F.Mask" "F.Paste")
			(net "RST_PERST_OCP_V3_2_R_N")
		)
		(pad "2" smd rect
			(at -1.199896 0 180)
			(size 0.5588 0.8128)
			(layers "F.Cu" "F.Mask" "F.Paste")
			(net "HP_LVC3_OCP_V3_2_PWRGD")
		)
		(pad "3" smd rect
			(at -1.199896 0.94996 180)
			(size 0.5588 0.8128)
			(layers "F.Cu" "F.Mask" "F.Paste")
			(net "GND")
		)
		(pad "4" smd rect
			(at 1.199896 0.94996 180)
			(size 0.5588 0.8128)
			(layers "F.Cu" "F.Mask" "F.Paste")
			(net "RST_PERST_OCP_V3_2_BUF_R_N")
		)
		(pad "5" smd rect
			(at 1.199896 -0.94996 180)
			(size 0.5588 0.8128)
			(layers "F.Cu" "F.Mask" "F.Paste")
			(net "P3V3_AUX")
		)
	)
)
